# BASEBOARD_FAB2 (Tioga Pass) — schematic netlist excerpt (pin names and nets, part order shuffled) for the footprints in the layout excerpt that follows; sources: Cadence DE-HDL packaged netlist, KiCad conversion of Wiwynn_Tioga_Pass_MB.brd

J1A2  SCONN288_H44441004  SCONN  pkg PIP  page 85
  \12v\(1)  = P12V_NVDIMM_KLM
  VSS(93)  = GND
  DQ(4)  = M_L_DQ<5>
  VSS(92)  = GND
  DQ(0)  = M_L_DQ<1>
  VSS(91)  = GND
  DQS9P  = M_L_DQS_DP<9>
  DQS9N  = M_L_DQS_DN<9>
  VSS(90)  = GND
  DQ(6)  = M_L_DQ<7>
  VSS(89)  = GND
  DQ(2)  = M_L_DQ<3>
  VSS(88)  = GND
  DQ(12)  = M_L_DQ<13>
  VSS(87)  = GND
  DQ(8)  = M_L_DQ<9>
  VSS(86)  = GND
  DQS10P  = M_L_DQS_DP<10>
  DQS10N  = M_L_DQS_DN<10>
  VSS(85)  = GND
  DQ(14)  = M_L_DQ<15>
  VSS(84)  = GND
  DQ(10)  = M_L_DQ<11>
  VSS(83)  = GND
  DQ(20)  = M_L_DQ<21>
  VSS(82)  = GND
  DQ(16)  = M_L_DQ<17>
  VSS(81)  = GND
  DQS11P  = M_L_DQS_DP<11>
  DQS11N  = M_L_DQS_DN<11>
  VSS(80)  = GND
  DQ(22)  = M_L_DQ<23>
  VSS(79)  = GND
  DQ(18)  = M_L_DQ<19>
  VSS(78)  = GND
  DQ(28)  = M_L_DQ<29>
  VSS(77)  = GND
  DQ(24)  = M_L_DQ<25>
  VSS(76)  = GND
  DQS12P  = M_L_DQS_DP<12>
  DQS12N  = M_L_DQS_DN<12>
  VSS(75)  = GND
  DQ(30)  = M_L_DQ<31>
  VSS(74)  = GND
  DQ(26)  = M_L_DQ<27>
  VSS(73)  = GND
  CB(4)  = M_L_ECC<5>
  VSS(72)  = GND
  CB(0)  = M_L_ECC<1>
  VSS(71)  = GND
  DQS17P  = M_L_DQS_DP<17>
  DQS17N  = M_L_DQS_DN<17>
  VSS(70)  = GND
  CB(6)  = M_L_ECC<7>
  VSS(69)  = GND
  CB(2)  = M_L_ECC<3>
  VSS(68)  = GND
  RESET_N  = M_KLM_RST_N
  VDD(25)  = PVDDQ_KLM
  CKE(0)  = M_L_CKE<0>
  VDD(24)  = PVDDQ_KLM
  ACT_N  = M_L_ACT_N
  BG(0)  = M_L_BG<0>
  VDD(23)  = PVDDQ_KLM
  A12  = M_L_MA<12>
  A9  = M_L_MA<9>
  VDD(22)  = PVDDQ_KLM
  A8  = M_L_MA<8>
  A6  = M_L_MA<6>
  VDD(21)  = PVDDQ_KLM
  A3  = M_L_MA<3>
  A1  = M_L_MA<1>
  VDD(20)  = PVDDQ_KLM
  CK0P  = M_L_CLK_DP<0>
  CK0N  = M_L_CLK_DN<0>
  VDD(19)  = PVDDQ_KLM
  VTT(1)  = PVTT_KLM
  EVENT_N  = FM_DIMM_EVENT_COD_N
  A0  = M_L_MA<0>
  VDD(18)  = PVDDQ_KLM
  BA(0)  = M_L_BA<0>
  A16_RAS_N  = M_L_MA<16>
  VDD(17)  = PVDDQ_KLM
  S0_N  = M_L_CS_N<0>
  VDD(16)  = PVDDQ_KLM
  A15_CAS_N  = M_L_MA<15>
  ODT(0)  = M_L_ODT<0>
  VDD(15)  = PVDDQ_KLM
  S1_N  = M_L_CS_N<1>
  VDD(14)  = PVDDQ_KLM
  ODT(1)  = M_L_ODT<1>
  VDD(13)  = PVDDQ_KLM
  S2_N_C(0)  = M_L_CS_N<2>
  VSS(67)  = GND
  DQ(36)  = M_L_DQ<37>
  VSS(66)  = GND
  DQ(32)  = M_L_DQ<33>
  VSS(65)  = GND
  DQS13P  = M_L_DQS_DP<13>
  DQS13N  = M_L_DQS_DN<13>
  VSS(64)  = GND
  DQ(38)  = M_L_DQ<39>
  VSS(63)  = GND
  DQ(34)  = M_L_DQ<35>
  VSS(62)  = GND
  DQ(44)  = M_L_DQ<45>
  VSS(61)  = GND
  DQ(40)  = M_L_DQ<41>
  VSS(60)  = GND
  DQS14P  = M_L_DQS_DP<14>
  DQS14N  = M_L_DQS_DN<14>
  VSS(59)  = GND
  DQ(46)  = M_L_DQ<47>
  VSS(58)  = GND
  DQ(42)  = M_L_DQ<43>
  VSS(57)  = GND
  DQ(52)  = M_L_DQ<53>
  VSS(56)  = GND
  DQ(48)  = M_L_DQ<49>
  VSS(55)  = GND
  DQS15P  = M_L_DQS_DP<15>
  DQS15N  = M_L_DQS_DN<15>
  VSS(54)  = GND
  DQ(54)  = M_L_DQ<55>
  VSS(53)  = GND
  DQ(50)  = M_L_DQ<51>
  VSS(52)  = GND
  DQ(60)  = M_L_DQ<61>
  VSS(51)  = GND
  DQ(56)  = M_L_DQ<57>
  VSS(50)  = GND
  DQS16P  = M_L_DQS_DP<16>
  DQS16N  = M_L_DQS_DN<16>
  VSS(49)  = GND
  DQ(62)  = M_L_DQ<63>
  VSS(48)  = GND
  DQ(58)  = M_L_DQ<59>
  VSS(47)  = GND
  SA(0)  = GND
  SA(1)  = PVPP_KLM
  SCL  = SMB_DDR_KLM_VPP_SCL
  VPP(4)  = PVPP_KLM
  VPP(3)  = PVPP_KLM
  RFU(2)  = TP_CH_L_DIMM_L0_RFU_2
  \12v\(0)  = P12V_NVDIMM_KLM
  VREFCA  = M_L_VREF
  VSS(46)  = GND
  DQ(5)  = M_L_DQ<4>
  VSS(45)  = GND
  DQ(1)  = M_L_DQ<0>
  VSS(44)  = GND
  DQS0N  = M_L_DQS_DN<0>
  DQS0P  = M_L_DQS_DP<0>
  VSS(43)  = GND
  DQ(7)  = M_L_DQ<6>
  VSS(42)  = GND
  DQ(3)  = M_L_DQ<2>
  VSS(41)  = GND
  DQ(13)  = M_L_DQ<12>
  VSS(40)  = GND
  DQ(9)  = M_L_DQ<8>
  VSS(39)  = GND
  DQS1N  = M_L_DQS_DN<1>
  DQS1P  = M_L_DQS_DP<1>
  VSS(38)  = GND
  DQ(15)  = M_L_DQ<14>
  VSS(37)  = GND
  DQ(11)  = M_L_DQ<10>
  VSS(36)  = GND
  DQ(21)  = M_L_DQ<20>
  VSS(35)  = GND
  DQ(17)  = M_L_DQ<16>
  VSS(34)  = GND
  DQS2N  = M_L_DQS_DN<2>
  DQS2P  = M_L_DQS_DP<2>
  VSS(33)  = GND
  DQ(23)  = M_L_DQ<22>
  VSS(32)  = GND
  DQ(19)  = M_L_DQ<18>
  VSS(31)  = GND
  DQ(29)  = M_L_DQ<28>
  VSS(30)  = GND
  DQ(25)  = M_L_DQ<24>
  VSS(29)  = GND
  DQS3N  = M_L_DQS_DN<3>
  DQS3P  = M_L_DQS_DP<3>
  VSS(28)  = GND
  DQ(31)  = M_L_DQ<30>
  VSS(27)  = GND
  DQ(27)  = M_L_DQ<26>
  VSS(26)  = GND
  CB(5)  = M_L_ECC<4>
  VSS(25)  = GND
  CB(1)  = M_L_ECC<0>
  VSS(24)  = GND
  DQS8N  = M_L_DQS_DN<8>
  DQS8P  = M_L_DQS_DP<8>
  VSS(23)  = GND
  CB(7)  = M_L_ECC<6>
  VSS(22)  = GND
  CB(3)  = M_L_ECC<2>
  VSS(21)  = GND
  CKE(1)  = M_L_CKE<1>
  VDD(12)  = PVDDQ_KLM
  RFU(0)  = TP_CH_L_DIMM_L0_RFU_0
  VDD(11)  = PVDDQ_KLM
  BG(1)  = M_L_BG<1>
  ALERT_N  = M_L_ALERT_N
  VDD(10)  = PVDDQ_KLM
  A11  = M_L_MA<11>
  A7  = M_L_MA<7>
  VDD(9)  = PVDDQ_KLM
  A5  = M_L_MA<5>
  A4  = M_L_MA<4>
  VDD(8)  = PVDDQ_KLM
  A2  = M_L_MA<2>
  VDD(7)  = PVDDQ_KLM
  CK1P  = M_L_CLK_DP<1>
  CK1N  = M_L_CLK_DN<1>
  VDD(6)  = PVDDQ_KLM
  VTT(0)  = PVTT_KLM
  PAR  = M_L_PAR
  VDD(5)  = PVDDQ_KLM
  BA(1)  = M_L_BA<1>
  A10  = M_L_MA<10>
  VDD(4)  = PVDDQ_KLM
  RFU(1)  = TP_CH_L_DIMM_L0_RFU_1
  A14_WE_N  = M_L_MA<14>
  VDD(3)  = PVDDQ_KLM
  SAVE_N_NC  = FM_ADR_COMPLETE_KLM_N
  VDD(2)  = PVDDQ_KLM
  A13  = M_L_MA<13>
  VDD(1)  = PVDDQ_KLM
  A17  = M_L_MA<17>
  C(2)  = M_L_C<2>
  VDD(0)  = PVDDQ_KLM
  S3_N_C(1)  = M_L_CS_N<3>
  SA(2)  = GND
  VSS(20)  = GND
  DQ(37)  = M_L_DQ<36>
  VSS(19)  = GND
  DQ(33)  = M_L_DQ<32>
  VSS(18)  = GND
  DQS4N  = M_L_DQS_DN<4>
  DQS4P  = M_L_DQS_DP<4>
  VSS(17)  = GND
  DQ(39)  = M_L_DQ<38>
  VSS(16)  = GND
  DQ(35)  = M_L_DQ<34>
  VSS(15)  = GND
  DQ(45)  = M_L_DQ<44>
  VSS(14)  = GND
  DQ(41)  = M_L_DQ<40>
  VSS(13)  = GND
  DQS5N  = M_L_DQS_DN<5>
  DQS5P  = M_L_DQS_DP<5>
  VSS(12)  = GND
  DQ(47)  = M_L_DQ<46>
  VSS(11)  = GND
  DQ(43)  = M_L_DQ<42>
  VSS(10)  = GND
  DQ(53)  = M_L_DQ<52>
  VSS(9)  = GND
  DQ(49)  = M_L_DQ<48>
  VSS(8)  = GND
  DQS6N  = M_L_DQS_DN<6>
  DQS6P  = M_L_DQS_DP<6>
  VSS(7)  = GND
  DQ(55)  = M_L_DQ<54>
  VSS(6)  = GND
  DQ(51)  = M_L_DQ<50>
  VSS(5)  = GND
  DQ(61)  = M_L_DQ<60>
  VSS(4)  = GND
  DQ(57)  = M_L_DQ<56>
  VSS(3)  = GND
  DQS7N  = M_L_DQS_DN<7>
  DQS7P  = M_L_DQS_DP<7>
  VSS(2)  = GND
  DQ(63)  = M_L_DQ<62>
  VSS(1)  = GND
  DQ(59)  = M_L_DQ<58>
  VSS(0)  = GND
  VDDSPD  = PVPP_KLM
  SDA  = SMB_DDR_KLM_VPP_SDA
  VPP(1)  = PVPP_KLM
  VPP(0)  = PVPP_KLM
  VPP(2)  = PVPP_KLM

(kicad_pcb
	(version 20260206)
	(generator "pcbnew")
	(generator_version "10.0")
	(general
		(thickness 1.6)
		(legacy_teardrops no)
	)
	(paper "A4")
	(title_block
		(title "Wiwynn_Tioga_Pass_MB.brd")
		(comment 1 "Tioga Pass / footprint 2031 of 4770 (J1A2), pads 203-251 of 291")
	)
	(layers
		(0 "F.Cu" signal "TOP")
		(4 "In1.Cu" signal "L2GND")
		(6 "In2.Cu" signal "L3")
		(8 "In3.Cu" signal "L4GND")
		(10 "In4.Cu" signal "L5")
		(12 "In5.Cu" signal "L6GND")
		(14 "In6.Cu" signal "L7VCC")
		(16 "In7.Cu" signal "L8VCC")
		(18 "In8.Cu" signal "L9GND")
		(20 "In9.Cu" signal "L10")
		(22 "In10.Cu" signal "L11GND")
		(24 "In11.Cu" signal "L12")
		(26 "In12.Cu" signal "L13GND")
		(2 "B.Cu" signal "BOTTOM")
		(9 "F.Adhes" user "F.Adhesive")
		(11 "B.Adhes" user "B.Adhesive")
		(13 "F.Paste" user "Package Geometry/Pastemask Top")
		(15 "B.Paste" user "Package Geometry/Pastemask Bottom")
		(5 "F.SilkS" user "Ref Des/Silkscreen Top")
		(7 "B.SilkS" user "Ref Des/Silkscreen Bottom")
		(1 "F.Mask" user "Board Geometry/Soldermask Top")
		(3 "B.Mask" user "Board Geometry/Soldermask Bottom")
		(17 "Dwgs.User" user "User.Drawings")
		(19 "Cmts.User" user "User.Comments")
		(21 "Eco1.User" user "User.Eco1")
		(23 "Eco2.User" user "User.Eco2")
		(25 "Edge.Cuts" user "Board Geometry/Outline")
		(27 "Margin" user)
		(31 "F.CrtYd" user "Package Geometry/Place Bound Top")
		(29 "B.CrtYd" user "Package Geometry/Place Bound Bottom")
		(35 "F.Fab" user "Ref Des/Assembly Top")
		(33 "B.Fab" user "Ref Des/Assembly Bottom")
	)
	(footprint ""
		(layer "F.Cu")
		(at 29.699458 -142.6718 90)
		(property "Reference" "J1A2"
			(at -2.623312 42.436542 0)
			(unlocked yes)
			(layer "F.SilkS")
			(effects
				(font
					(size 0.7874 0.5842)
					(thickness 0.1524)
				)
				(justify left)
			)
		)
		(property "Value" ""
			(at 0 0 90)
			(layer "F.Fab")
			(effects
				(font
					(size 1.27 1.27)
				)
			)
		)
		(duplicate_pad_numbers_are_jumpers no)
		(pad "200" smd rect
			(at 4.59994 46.74997 90)
			(size 1.8034 0.508)
			(layers "F.Cu" "F.Mask" "F.Paste")
			(net "GND")
		)
		(pad "201" smd rect
			(at 4.59994 47.600108 90)
			(size 1.8034 0.508)
			(layers "F.Cu" "F.Mask" "F.Paste")
			(net "M_L_ECC<2>")
		)
		(pad "202" smd rect
			(at 4.59994 48.449992 90)
			(size 1.8034 0.508)
			(layers "F.Cu" "F.Mask" "F.Paste")
			(net "GND")
		)
		(pad "203" smd rect
			(at 4.59994 49.299876 90)
			(size 1.8034 0.508)
			(layers "F.Cu" "F.Mask" "F.Paste")
			(net "M_L_CKE<1>")
		)
		(pad "204" smd rect
			(at 4.59994 50.150014 90)
			(size 1.8034 0.508)
			(layers "F.Cu" "F.Mask" "F.Paste")
			(net "PVDDQ_KLM")
		)
		(pad "205" smd rect
			(at 4.59994 50.999898 90)
			(size 1.8034 0.508)
			(layers "F.Cu" "F.Mask" "F.Paste")
			(net "TP_CH_L_DIMM_L0_RFU_0")
		)
		(pad "206" smd rect
			(at 4.59994 51.850036 90)
			(size 1.8034 0.508)
			(layers "F.Cu" "F.Mask" "F.Paste")
			(net "PVDDQ_KLM")
		)
		(pad "207" smd rect
			(at 4.59994 52.69992 90)
			(size 1.8034 0.508)
			(layers "F.Cu" "F.Mask" "F.Paste")
			(net "M_L_BG<1>")
		)
		(pad "208" smd rect
			(at 4.59994 53.550058 90)
			(size 1.8034 0.508)
			(layers "F.Cu" "F.Mask" "F.Paste")
			(net "M_L_ALERT_N")
		)
		(pad "209" smd rect
			(at 4.59994 54.399942 90)
			(size 1.8034 0.508)
			(layers "F.Cu" "F.Mask" "F.Paste")
			(net "PVDDQ_KLM")
		)
		(pad "210" smd rect
			(at 4.59994 55.25008 90)
			(size 1.8034 0.508)
			(layers "F.Cu" "F.Mask" "F.Paste")
			(net "M_L_MA<11>")
		)
		(pad "211" smd rect
			(at 4.59994 56.099964 90)
			(size 1.8034 0.508)
			(layers "F.Cu" "F.Mask" "F.Paste")
			(net "M_L_MA<7>")
		)
		(pad "212" smd rect
			(at 4.59994 56.950102 90)
			(size 1.8034 0.508)
			(layers "F.Cu" "F.Mask" "F.Paste")
			(net "PVDDQ_KLM")
		)
		(pad "213" smd rect
			(at 4.59994 57.799986 90)
			(size 1.8034 0.508)
			(layers "F.Cu" "F.Mask" "F.Paste")
			(net "M_L_MA<5>")
		)
		(pad "214" smd rect
			(at 4.59994 58.650124 90)
			(size 1.8034 0.508)
			(layers "F.Cu" "F.Mask" "F.Paste")
			(net "M_L_MA<4>")
		)
		(pad "215" smd rect
			(at 4.59994 59.500008 90)
			(size 1.8034 0.508)
			(layers "F.Cu" "F.Mask" "F.Paste")
			(net "PVDDQ_KLM")
		)
		(pad "216" smd rect
			(at 4.59994 60.349892 90)
			(size 1.8034 0.508)
			(layers "F.Cu" "F.Mask" "F.Paste")
			(net "M_L_MA<2>")
		)
		(pad "217" smd rect
			(at 4.59994 61.20003 90)
			(size 1.8034 0.508)
			(layers "F.Cu" "F.Mask" "F.Paste")
			(net "PVDDQ_KLM")
		)
		(pad "218" smd rect
			(at 4.59994 62.049914 90)
			(size 1.8034 0.508)
			(layers "F.Cu" "F.Mask" "F.Paste")
			(net "M_L_CLK_DP<1>")
		)
		(pad "219" smd rect
			(at 4.59994 62.900052 90)
			(size 1.8034 0.508)
			(layers "F.Cu" "F.Mask" "F.Paste")
			(net "M_L_CLK_DN<1>")
		)
		(pad "220" smd rect
			(at 4.59994 63.749936 90)
			(size 1.8034 0.508)
			(layers "F.Cu" "F.Mask" "F.Paste")
			(net "PVDDQ_KLM")
		)
		(pad "221" smd rect
			(at 4.59994 64.600074 90)
			(size 1.8034 0.508)
			(layers "F.Cu" "F.Mask" "F.Paste")
			(net "PVTT_KLM")
		)
		(pad "222" smd rect
			(at 4.59994 70.550024 90)
			(size 1.8034 0.508)
			(layers "F.Cu" "F.Mask" "F.Paste")
			(net "M_L_PAR")
		)
		(pad "223" smd rect
			(at 4.59994 71.399908 90)
			(size 1.8034 0.508)
			(layers "F.Cu" "F.Mask" "F.Paste")
			(net "PVDDQ_KLM")
		)
		(pad "224" smd rect
			(at 4.59994 72.250046 90)
			(size 1.8034 0.508)
			(layers "F.Cu" "F.Mask" "F.Paste")
			(net "M_L_BA<1>")
		)
		(pad "225" smd rect
			(at 4.59994 73.09993 90)
			(size 1.8034 0.508)
			(layers "F.Cu" "F.Mask" "F.Paste")
			(net "M_L_MA<10>")
		)
		(pad "226" smd rect
			(at 4.59994 73.950068 90)
			(size 1.8034 0.508)
			(layers "F.Cu" "F.Mask" "F.Paste")
			(net "PVDDQ_KLM")
		)
		(pad "227" smd rect
			(at 4.59994 74.799952 90)
			(size 1.8034 0.508)
			(layers "F.Cu" "F.Mask" "F.Paste")
			(net "TP_CH_L_DIMM_L0_RFU_1")
		)
		(pad "228" smd rect
			(at 4.59994 75.65009 90)
			(size 1.8034 0.508)
			(layers "F.Cu" "F.Mask" "F.Paste")
			(net "M_L_MA<14>")
		)
		(pad "229" smd rect
			(at 4.59994 76.499974 90)
			(size 1.8034 0.508)
			(layers "F.Cu" "F.Mask" "F.Paste")
			(net "PVDDQ_KLM")
		)
		(pad "230" smd rect
			(at 4.59994 77.350112 90)
			(size 1.8034 0.508)
			(layers "F.Cu" "F.Mask" "F.Paste")
			(net "FM_ADR_COMPLETE_KLM_N")
		)
		(pad "231" smd rect
			(at 4.59994 78.199996 90)
			(size 1.8034 0.508)
			(layers "F.Cu" "F.Mask" "F.Paste")
			(net "PVDDQ_KLM")
		)
		(pad "232" smd rect
			(at 4.59994 79.04988 90)
			(size 1.8034 0.508)
			(layers "F.Cu" "F.Mask" "F.Paste")
			(net "M_L_MA<13>")
		)
		(pad "233" smd rect
			(at 4.59994 79.900018 90)
			(size 1.8034 0.508)
			(layers "F.Cu" "F.Mask" "F.Paste")
			(net "PVDDQ_KLM")
		)
		(pad "234" smd rect
			(at 4.59994 80.749902 90)
			(size 1.8034 0.508)
			(layers "F.Cu" "F.Mask" "F.Paste")
			(net "M_L_MA<17>")
		)
		(pad "235" smd rect
			(at 4.59994 81.60004 90)
			(size 1.8034 0.508)
			(layers "F.Cu" "F.Mask" "F.Paste")
			(net "M_L_C<2>")
		)
		(pad "236" smd rect
			(at 4.59994 82.449924 90)
			(size 1.8034 0.508)
			(layers "F.Cu" "F.Mask" "F.Paste")
			(net "PVDDQ_KLM")
		)
		(pad "237" smd rect
			(at 4.59994 83.300062 90)
			(size 1.8034 0.508)
			(layers "F.Cu" "F.Mask" "F.Paste")
			(net "M_L_CS_N<3>")
		)
		(pad "238" smd rect
			(at 4.59994 84.149946 90)
			(size 1.8034 0.508)
			(layers "F.Cu" "F.Mask" "F.Paste")
			(net "GND")
		)
		(pad "239" smd rect
			(at 4.59994 85.000084 90)
			(size 1.8034 0.508)
			(layers "F.Cu" "F.Mask" "F.Paste")
			(net "GND")
		)
		(pad "240" smd rect
			(at 4.59994 85.849968 90)
			(size 1.8034 0.508)
			(layers "F.Cu" "F.Mask" "F.Paste")
			(net "M_L_DQ<36>")
		)
		(pad "241" smd rect
			(at 4.59994 86.700106 90)
			(size 1.8034 0.508)
			(layers "F.Cu" "F.Mask" "F.Paste")
			(net "GND")
		)
		(pad "242" smd rect
			(at 4.59994 87.54999 90)
			(size 1.8034 0.508)
			(layers "F.Cu" "F.Mask" "F.Paste")
			(net "M_L_DQ<32>")
		)
		(pad "243" smd rect
			(at 4.59994 88.399874 90)
			(size 1.8034 0.508)
			(layers "F.Cu" "F.Mask" "F.Paste")
			(net "GND")
		)
		(pad "244" smd rect
			(at 4.59994 89.250012 90)
			(size 1.8034 0.508)
			(layers "F.Cu" "F.Mask" "F.Paste")
			(net "M_L_DQS_DN<4>")
		)
		(pad "245" smd rect
			(at 4.59994 90.099896 90)
			(size 1.8034 0.508)
			(layers "F.Cu" "F.Mask" "F.Paste")
			(net "M_L_DQS_DP<4>")
		)
		(pad "246" smd rect
			(at 4.59994 90.950034 90)
			(size 1.8034 0.508)
			(layers "F.Cu" "F.Mask" "F.Paste")
			(net "GND")
		)
		(pad "247" smd rect
			(at 4.59994 91.799918 90)
			(size 1.8034 0.508)
			(layers "F.Cu" "F.Mask" "F.Paste")
			(net "M_L_DQ<38>")
		)
		(pad "248" smd rect
			(at 4.59994 92.650056 90)
			(size 1.8034 0.508)
			(layers "F.Cu" "F.Mask" "F.Paste")
			(net "GND")
		)
	)
)
